(kicad_pcb
	(version 20260206)
	(generator "pcbnew")
	(generator_version "10.0")
	(general
		(thickness 1.6)
		(legacy_teardrops no)
	)
	(paper "A4")
	(title_block
		(title "12092022_DA0F0TMDCD0_F0T_Management_Board_D_brd_V3_OCP.brd")
		(comment 1 "Grand Teton / footprints 485-490 of 1440")
	)
	(layers
		(0 "F.Cu" signal "TOP")
		(4 "In1.Cu" signal "GND")
		(6 "In2.Cu" signal "IN1")
		(8 "In3.Cu" signal "GND1")
		(10 "In4.Cu" signal "IN2")
		(12 "In5.Cu" signal "VCC")
		(14 "In6.Cu" signal "VCC1")
		(16 "In7.Cu" signal "IN3")
		(18 "In8.Cu" signal "GND2")
		(20 "In9.Cu" signal "IN4")
		(22 "In10.Cu" signal "GND3")
		(2 "B.Cu" signal "BOTTOM")
		(9 "F.Adhes" user "F.Adhesive")
		(11 "B.Adhes" user "B.Adhesive")
		(13 "F.Paste" user "Package Geometry/Pastemask Top")
		(15 "B.Paste" user "Package Geometry/Pastemask Bottom")
		(5 "F.SilkS" user "Ref Des/Silkscreen Top")
		(7 "B.SilkS" user "Ref Des/Silkscreen Bottom")
		(1 "F.Mask" user "Board Geometry/Soldermask Top")
		(3 "B.Mask" user "Board Geometry/Soldermask Bottom")
		(17 "Dwgs.User" user "User.Drawings")
		(19 "Cmts.User" user "User.Comments")
		(21 "Eco1.User" user "User.Eco1")
		(23 "Eco2.User" user "User.Eco2")
		(25 "Edge.Cuts" user "Board Geometry/Outline")
		(27 "Margin" user)
		(31 "F.CrtYd" user "Package Geometry/Place Bound Top")
		(29 "B.CrtYd" user "Package Geometry/Place Bound Bottom")
		(35 "F.Fab" user "Ref Des/Assembly Top")
		(33 "B.Fab" user "Ref Des/Assembly Bottom")
	)
	(footprint ""
		(layer "F.Cu")
		(at 69.4055 -69.596 -90)
		(property "Reference" "R460"
			(at 0 0 270)
			(layer "F.SilkS")
			(hide yes)
			(effects
				(font
					(size 1.27 1.27)
				)
			)
		)
		(property "Value" ""
			(at 0 0 270)
			(layer "F.Fab")
			(effects
				(font
					(size 1.27 1.27)
				)
			)
		)
		(duplicate_pad_numbers_are_jumpers no)
		(fp_line
			(start -0.7874 0.4064)
			(end -0.7874 -0.4064)
			(stroke
				(width 0.1524)
				(type default)
			)
			(layer "F.SilkS")
		)
		(fp_line
			(start 0.7874 0.4064)
			(end -0.7874 0.4064)
			(stroke
				(width 0.1524)
				(type default)
			)
			(layer "F.SilkS")
		)
		(fp_line
			(start -0.7874 -0.4064)
			(end 0.7874 -0.4064)
			(stroke
				(width 0.1524)
				(type default)
			)
			(layer "F.SilkS")
		)
		(fp_line
			(start 0.7874 -0.4064)
			(end 0.7874 0.4064)
			(stroke
				(width 0.1524)
				(type default)
			)
			(layer "F.SilkS")
		)
		(fp_line
			(start -0.67945 0.3048)
			(end -0.67945 -0.305054)
			(stroke
				(width 0.1)
				(type default)
			)
			(layer "F.Fab")
		)
		(fp_line
			(start -0.12065 0.3048)
			(end -0.67945 0.3048)
			(stroke
				(width 0.1)
				(type default)
			)
			(layer "F.Fab")
		)
		(fp_line
			(start 0.120396 0.3048)
			(end 0.120396 0.2794)
			(stroke
				(width 0.1)
				(type default)
			)
			(layer "F.Fab")
		)
		(fp_line
			(start 0.67945 0.3048)
			(end 0.120396 0.3048)
			(stroke
				(width 0.1)
				(type default)
			)
			(layer "F.Fab")
		)
		(fp_line
			(start -0.12065 0.2794)
			(end -0.12065 0.3048)
			(stroke
				(width 0.1)
				(type default)
			)
			(layer "F.Fab")
		)
		(fp_line
			(start 0.120396 0.2794)
			(end -0.12065 0.2794)
			(stroke
				(width 0.1)
				(type default)
			)
			(layer "F.Fab")
		)
		(fp_line
			(start -0.12065 -0.2794)
			(end 0.12065 -0.2794)
			(stroke
				(width 0.1)
				(type default)
			)
			(layer "F.Fab")
		)
		(fp_line
			(start 0.12065 -0.2794)
			(end 0.12065 -0.3048)
			(stroke
				(width 0.1)
				(type default)
			)
			(layer "F.Fab")
		)
		(fp_line
			(start 0.12065 -0.3048)
			(end 0.67945 -0.3048)
			(stroke
				(width 0.1)
				(type default)
			)
			(layer "F.Fab")
		)
		(fp_line
			(start 0.67945 -0.3048)
			(end 0.67945 0.3048)
			(stroke
				(width 0.1)
				(type default)
			)
			(layer "F.Fab")
		)
		(fp_line
			(start -0.67945 -0.305054)
			(end -0.12065 -0.305054)
			(stroke
				(width 0.1)
				(type default)
			)
			(layer "F.Fab")
		)
		(fp_line
			(start -0.12065 -0.305054)
			(end -0.12065 -0.2794)
			(stroke
				(width 0.1)
				(type default)
			)
			(layer "F.Fab")
		)
		(pad "1" smd circle
			(at -0.40005 0 270)
			(size 0 0)
			(layers "F.Cu" "F.Mask" "F.Paste")
			(net "SPI_BMC_TPM_CS2_R_N")
		)
		(pad "2" smd circle
			(at 0.40005 0 270)
			(size 0 0)
			(layers "F.Cu" "F.Mask" "F.Paste")
			(net "SPI_BMC_TPM_CS2_R1_N")
		)
	)
	(footprint ""
		(layer "F.Cu")
		(at 37.6936 -42.1894 -90)
		(property "Reference" "R268"
			(at 0 0 270)
			(layer "F.SilkS")
			(hide yes)
			(effects
				(font
					(size 1.27 1.27)
				)
			)
		)
		(property "Value" ""
			(at 0 0 270)
			(layer "F.Fab")
			(effects
				(font
					(size 1.27 1.27)
				)
			)
		)
		(duplicate_pad_numbers_are_jumpers no)
		(fp_line
			(start -0.7874 0.4064)
			(end -0.7874 -0.4064)
			(stroke
				(width 0.1524)
				(type default)
			)
			(layer "F.SilkS")
		)
		(fp_line
			(start 0.7874 0.4064)
			(end -0.7874 0.4064)
			(stroke
				(width 0.1524)
				(type default)
			)
			(layer "F.SilkS")
		)
		(fp_line
			(start -0.7874 -0.4064)
			(end 0.7874 -0.4064)
			(stroke
				(width 0.1524)
				(type default)
			)
			(layer "F.SilkS")
		)
		(fp_line
			(start 0.7874 -0.4064)
			(end 0.7874 0.4064)
			(stroke
				(width 0.1524)
				(type default)
			)
			(layer "F.SilkS")
		)
		(fp_line
			(start -0.67945 0.3048)
			(end -0.67945 -0.305054)
			(stroke
				(width 0.1)
				(type default)
			)
			(layer "F.Fab")
		)
		(fp_line
			(start -0.12065 0.3048)
			(end -0.67945 0.3048)
			(stroke
				(width 0.1)
				(type default)
			)
			(layer "F.Fab")
		)
		(fp_line
			(start 0.120396 0.3048)
			(end 0.120396 0.2794)
			(stroke
				(width 0.1)
				(type default)
			)
			(layer "F.Fab")
		)
		(fp_line
			(start 0.67945 0.3048)
			(end 0.120396 0.3048)
			(stroke
				(width 0.1)
				(type default)
			)
			(layer "F.Fab")
		)
		(fp_line
			(start -0.12065 0.2794)
			(end -0.12065 0.3048)
			(stroke
				(width 0.1)
				(type default)
			)
			(layer "F.Fab")
		)
		(fp_line
			(start 0.120396 0.2794)
			(end -0.12065 0.2794)
			(stroke
				(width 0.1)
				(type default)
			)
			(layer "F.Fab")
		)
		(fp_line
			(start -0.12065 -0.2794)
			(end 0.12065 -0.2794)
			(stroke
				(width 0.1)
				(type default)
			)
			(layer "F.Fab")
		)
		(fp_line
			(start 0.12065 -0.2794)
			(end 0.12065 -0.3048)
			(stroke
				(width 0.1)
				(type default)
			)
			(layer "F.Fab")
		)
		(fp_line
			(start 0.12065 -0.3048)
			(end 0.67945 -0.3048)
			(stroke
				(width 0.1)
				(type default)
			)
			(layer "F.Fab")
		)
		(fp_line
			(start 0.67945 -0.3048)
			(end 0.67945 0.3048)
			(stroke
				(width 0.1)
				(type default)
			)
			(layer "F.Fab")
		)
		(fp_line
			(start -0.67945 -0.305054)
			(end -0.12065 -0.305054)
			(stroke
				(width 0.1)
				(type default)
			)
			(layer "F.Fab")
		)
		(fp_line
			(start -0.12065 -0.305054)
			(end -0.12065 -0.2794)
			(stroke
				(width 0.1)
				(type default)
			)
			(layer "F.Fab")
		)
		(pad "1" smd circle
			(at -0.40005 0 270)
			(size 0 0)
			(layers "F.Cu" "F.Mask" "F.Paste")
			(net "P3V3_AUX")
		)
		(pad "2" smd circle
			(at 0.40005 0 270)
			(size 0 0)
			(layers "F.Cu" "F.Mask" "F.Paste")
			(net "SMB_BMC_ALERT3_N")
		)
	)
	(footprint ""
		(layer "F.Cu")
		(at 29.591 -102.7684 -90)
		(property "Reference" "R45"
			(at 0 0 270)
			(layer "F.SilkS")
			(hide yes)
			(effects
				(font
					(size 1.27 1.27)
				)
			)
		)
		(property "Value" ""
			(at 0 0 270)
			(layer "F.Fab")
			(effects
				(font
					(size 1.27 1.27)
				)
			)
		)
		(duplicate_pad_numbers_are_jumpers no)
		(fp_line
			(start -0.7874 0.4064)
			(end -0.7874 -0.4064)
			(stroke
				(width 0.1524)
				(type default)
			)
			(layer "F.SilkS")
		)
		(fp_line
			(start 0.7874 0.4064)
			(end -0.7874 0.4064)
			(stroke
				(width 0.1524)
				(type default)
			)
			(layer "F.SilkS")
		)
		(fp_line
			(start -0.7874 -0.4064)
			(end 0.7874 -0.4064)
			(stroke
				(width 0.1524)
				(type default)
			)
			(layer "F.SilkS")
		)
		(fp_line
			(start 0.7874 -0.4064)
			(end 0.7874 0.4064)
			(stroke
				(width 0.1524)
				(type default)
			)
			(layer "F.SilkS")
		)
		(fp_line
			(start -0.67945 0.3048)
			(end -0.67945 -0.305054)
			(stroke
				(width 0.1)
				(type default)
			)
			(layer "F.Fab")
		)
		(fp_line
			(start -0.12065 0.3048)
			(end -0.67945 0.3048)
			(stroke
				(width 0.1)
				(type default)
			)
			(layer "F.Fab")
		)
		(fp_line
			(start 0.120396 0.3048)
			(end 0.120396 0.2794)
			(stroke
				(width 0.1)
				(type default)
			)
			(layer "F.Fab")
		)
		(fp_line
			(start 0.67945 0.3048)
			(end 0.120396 0.3048)
			(stroke
				(width 0.1)
				(type default)
			)
			(layer "F.Fab")
		)
		(fp_line
			(start -0.12065 0.2794)
			(end -0.12065 0.3048)
			(stroke
				(width 0.1)
				(type default)
			)
			(layer "F.Fab")
		)
		(fp_line
			(start 0.120396 0.2794)
			(end -0.12065 0.2794)
			(stroke
				(width 0.1)
				(type default)
			)
			(layer "F.Fab")
		)
		(fp_line
			(start -0.12065 -0.2794)
			(end 0.12065 -0.2794)
			(stroke
				(width 0.1)
				(type default)
			)
			(layer "F.Fab")
		)
		(fp_line
			(start 0.12065 -0.2794)
			(end 0.12065 -0.3048)
			(stroke
				(width 0.1)
				(type default)
			)
			(layer "F.Fab")
		)
		(fp_line
			(start 0.12065 -0.3048)
			(end 0.67945 -0.3048)
			(stroke
				(width 0.1)
				(type default)
			)
			(layer "F.Fab")
		)
		(fp_line
			(start 0.67945 -0.3048)
			(end 0.67945 0.3048)
			(stroke
				(width 0.1)
				(type default)
			)
			(layer "F.Fab")
		)
		(fp_line
			(start -0.67945 -0.305054)
			(end -0.12065 -0.305054)
			(stroke
				(width 0.1)
				(type default)
			)
			(layer "F.Fab")
		)
		(fp_line
			(start -0.12065 -0.305054)
			(end -0.12065 -0.2794)
			(stroke
				(width 0.1)
				(type default)
			)
			(layer "F.Fab")
		)
		(pad "1" smd circle
			(at -0.40005 0 270)
			(size 0 0)
			(layers "F.Cu" "F.Mask" "F.Paste")
			(net "P3V3_AUX")
		)
		(pad "2" smd circle
			(at 0.40005 0 270)
			(size 0 0)
			(layers "F.Cu" "F.Mask" "F.Paste")
			(net "FM_THROTTLE_N")
		)
	)
	(footprint ""
		(layer "F.Cu")
		(at 41.7576 -30.861 90)
		(property "Reference" "R455"
			(at 0 0 90)
			(layer "F.SilkS")
			(hide yes)
			(effects
				(font
					(size 1.27 1.27)
				)
			)
		)
		(property "Value" ""
			(at 0 0 90)
			(layer "F.Fab")
			(effects
				(font
					(size 1.27 1.27)
				)
			)
		)
		(duplicate_pad_numbers_are_jumpers no)
		(fp_line
			(start 0.7874 -0.4064)
			(end 0.7874 0.4064)
			(stroke
				(width 0.1524)
				(type default)
			)
			(layer "F.SilkS")
		)
		(fp_line
			(start -0.7874 -0.4064)
			(end 0.7874 -0.4064)
			(stroke
				(width 0.1524)
				(type default)
			)
			(layer "F.SilkS")
		)
		(fp_line
			(start 0.7874 0.4064)
			(end -0.7874 0.4064)
			(stroke
				(width 0.1524)
				(type default)
			)
			(layer "F.SilkS")
		)
		(fp_line
			(start -0.7874 0.4064)
			(end -0.7874 -0.4064)
			(stroke
				(width 0.1524)
				(type default)
			)
			(layer "F.SilkS")
		)
		(fp_line
			(start -0.12065 -0.305054)
			(end -0.12065 -0.2794)
			(stroke
				(width 0.1)
				(type default)
			)
			(layer "F.Fab")
		)
		(fp_line
			(start -0.67945 -0.305054)
			(end -0.12065 -0.305054)
			(stroke
				(width 0.1)
				(type default)
			)
			(layer "F.Fab")
		)
		(fp_line
			(start 0.67945 -0.3048)
			(end 0.67945 0.3048)
			(stroke
				(width 0.1)
				(type default)
			)
			(layer "F.Fab")
		)
		(fp_line
			(start 0.12065 -0.3048)
			(end 0.67945 -0.3048)
			(stroke
				(width 0.1)
				(type default)
			)
			(layer "F.Fab")
		)
		(fp_line
			(start 0.12065 -0.2794)
			(end 0.12065 -0.3048)
			(stroke
				(width 0.1)
				(type default)
			)
			(layer "F.Fab")
		)
		(fp_line
			(start -0.12065 -0.2794)
			(end 0.12065 -0.2794)
			(stroke
				(width 0.1)
				(type default)
			)
			(layer "F.Fab")
		)
		(fp_line
			(start 0.120396 0.2794)
			(end -0.12065 0.2794)
			(stroke
				(width 0.1)
				(type default)
			)
			(layer "F.Fab")
		)
		(fp_line
			(start -0.12065 0.2794)
			(end -0.12065 0.3048)
			(stroke
				(width 0.1)
				(type default)
			)
			(layer "F.Fab")
		)
		(fp_line
			(start 0.67945 0.3048)
			(end 0.120396 0.3048)
			(stroke
				(width 0.1)
				(type default)
			)
			(layer "F.Fab")
		)
		(fp_line
			(start 0.120396 0.3048)
			(end 0.120396 0.2794)
			(stroke
				(width 0.1)
				(type default)
			)
			(layer "F.Fab")
		)
		(fp_line
			(start -0.12065 0.3048)
			(end -0.67945 0.3048)
			(stroke
				(width 0.1)
				(type default)
			)
			(layer "F.Fab")
		)
		(fp_line
			(start -0.67945 0.3048)
			(end -0.67945 -0.305054)
			(stroke
				(width 0.1)
				(type default)
			)
			(layer "F.Fab")
		)
		(pad "1" smd circle
			(at -0.40005 0 90)
			(size 0 0)
			(layers "F.Cu" "F.Mask" "F.Paste")
			(net "SMB_BMC_MM2_SCL")
		)
		(pad "2" smd circle
			(at 0.40005 0 90)
			(size 0 0)
			(layers "F.Cu" "F.Mask" "F.Paste")
			(net "SMB_BMC_MM2_SCL_R1")
		)
	)
	(footprint ""
		(layer "F.Cu")
		(at 12.319 -91.44 180)
		(property "Reference" "R888"
			(at 0 0 180)
			(layer "F.SilkS")
			(hide yes)
			(effects
				(font
					(size 1.27 1.27)
				)
			)
		)
		(property "Value" ""
			(at 0 0 180)
			(layer "F.Fab")
			(effects
				(font
					(size 1.27 1.27)
				)
			)
		)
		(duplicate_pad_numbers_are_jumpers no)
		(fp_line
			(start 0.7874 0.4064)
			(end -0.7874 0.4064)
			(stroke
				(width 0.1524)
				(type default)
			)
			(layer "F.SilkS")
		)
		(fp_line
			(start 0.7874 -0.4064)
			(end 0.7874 0.4064)
			(stroke
				(width 0.1524)
				(type default)
			)
			(layer "F.SilkS")
		)
		(fp_line
			(start -0.7874 0.4064)
			(end -0.7874 -0.4064)
			(stroke
				(width 0.1524)
				(type default)
			)
			(layer "F.SilkS")
		)
		(fp_line
			(start -0.7874 -0.4064)
			(end 0.7874 -0.4064)
			(stroke
				(width 0.1524)
				(type default)
			)
			(layer "F.SilkS")
		)
		(fp_line
			(start 0.67945 0.3048)
			(end 0.120396 0.3048)
			(stroke
				(width 0.1)
				(type default)
			)
			(layer "F.Fab")
		)
		(fp_line
			(start 0.67945 -0.3048)
			(end 0.67945 0.3048)
			(stroke
				(width 0.1)
				(type default)
			)
			(layer "F.Fab")
		)
		(fp_line
			(start 0.12065 -0.2794)
			(end 0.12065 -0.3048)
			(stroke
				(width 0.1)
				(type default)
			)
			(layer "F.Fab")
		)
		(fp_line
			(start 0.12065 -0.3048)
			(end 0.67945 -0.3048)
			(stroke
				(width 0.1)
				(type default)
			)
			(layer "F.Fab")
		)
		(fp_line
			(start 0.120396 0.3048)
			(end 0.120396 0.2794)
			(stroke
				(width 0.1)
				(type default)
			)
			(layer "F.Fab")
		)
		(fp_line
			(start 0.120396 0.2794)
			(end -0.12065 0.2794)
			(stroke
				(width 0.1)
				(type default)
			)
			(layer "F.Fab")
		)
		(fp_line
			(start -0.12065 0.3048)
			(end -0.67945 0.3048)
			(stroke
				(width 0.1)
				(type default)
			)
			(layer "F.Fab")
		)
		(fp_line
			(start -0.12065 0.2794)
			(end -0.12065 0.3048)
			(stroke
				(width 0.1)
				(type default)
			)
			(layer "F.Fab")
		)
		(fp_line
			(start -0.12065 -0.2794)
			(end 0.12065 -0.2794)
			(stroke
				(width 0.1)
				(type default)
			)
			(layer "F.Fab")
		)
		(fp_line
			(start -0.12065 -0.305054)
			(end -0.12065 -0.2794)
			(stroke
				(width 0.1)
				(type default)
			)
			(layer "F.Fab")
		)
		(fp_line
			(start -0.67945 0.3048)
			(end -0.67945 -0.305054)
			(stroke
				(width 0.1)
				(type default)
			)
			(layer "F.Fab")
		)
		(fp_line
			(start -0.67945 -0.305054)
			(end -0.12065 -0.305054)
			(stroke
				(width 0.1)
				(type default)
			)
			(layer "F.Fab")
		)
		(pad "1" smd rect
			(at -0.40005 0)
			(size 0.4572 0.508)
			(layers "F.Cu" "F.Mask" "F.Paste")
			(net "P3V3_AUX")
		)
		(pad "2" smd rect
			(at 0.40005 0)
			(size 0.4572 0.508)
			(layers "F.Cu" "F.Mask" "F.Paste")
			(net "RST_BMC_SELF_HW")
		)
	)
	(footprint ""
		(layer "F.Cu")
		(at 11.171936 -54.538372 180)
		(property "Reference" "PR241"
			(at 0 0 180)
			(layer "F.SilkS")
			(hide yes)
			(effects
				(font
					(size 1.27 1.27)
				)
			)
		)
		(property "Value" ""
			(at 0 0 180)
			(layer "F.Fab")
			(effects
				(font
					(size 1.27 1.27)
				)
			)
		)
		(duplicate_pad_numbers_are_jumpers no)
		(fp_line
			(start 0.7874 0.4064)
			(end -0.7874 0.4064)
			(stroke
				(width 0.1524)
				(type default)
			)
			(layer "F.SilkS")
		)
		(fp_line
			(start 0.7874 -0.4064)
			(end 0.7874 0.4064)
			(stroke
				(width 0.1524)
				(type default)
			)
			(layer "F.SilkS")
		)
		(fp_line
			(start -0.7874 0.4064)
			(end -0.7874 -0.4064)
			(stroke
				(width 0.1524)
				(type default)
			)
			(layer "F.SilkS")
		)
		(fp_line
			(start -0.7874 -0.4064)
			(end 0.7874 -0.4064)
			(stroke
				(width 0.1524)
				(type default)
			)
			(layer "F.SilkS")
		)
		(fp_line
			(start 0.67945 0.3048)
			(end 0.120396 0.3048)
			(stroke
				(width 0.1)
				(type default)
			)
			(layer "F.Fab")
		)
		(fp_line
			(start 0.67945 -0.3048)
			(end 0.67945 0.3048)
			(stroke
				(width 0.1)
				(type default)
			)
			(layer "F.Fab")
		)
		(fp_line
			(start 0.12065 -0.2794)
			(end 0.12065 -0.3048)
			(stroke
				(width 0.1)
				(type default)
			)
			(layer "F.Fab")
		)
		(fp_line
			(start 0.12065 -0.3048)
			(end 0.67945 -0.3048)
			(stroke
				(width 0.1)
				(type default)
			)
			(layer "F.Fab")
		)
		(fp_line
			(start 0.120396 0.3048)
			(end 0.120396 0.2794)
			(stroke
				(width 0.1)
				(type default)
			)
			(layer "F.Fab")
		)
		(fp_line
			(start 0.120396 0.2794)
			(end -0.12065 0.2794)
			(stroke
				(width 0.1)
				(type default)
			)
			(layer "F.Fab")
		)
		(fp_line
			(start -0.12065 0.3048)
			(end -0.67945 0.3048)
			(stroke
				(width 0.1)
				(type default)
			)
			(layer "F.Fab")
		)
		(fp_line
			(start -0.12065 0.2794)
			(end -0.12065 0.3048)
			(stroke
				(width 0.1)
				(type default)
			)
			(layer "F.Fab")
		)
		(fp_line
			(start -0.12065 -0.2794)
			(end 0.12065 -0.2794)
			(stroke
				(width 0.1)
				(type default)
			)
			(layer "F.Fab")
		)
		(fp_line
			(start -0.12065 -0.305054)
			(end -0.12065 -0.2794)
			(stroke
				(width 0.1)
				(type default)
			)
			(layer "F.Fab")
		)
		(fp_line
			(start -0.67945 0.3048)
			(end -0.67945 -0.305054)
			(stroke
				(width 0.1)
				(type default)
			)
			(layer "F.Fab")
		)
		(fp_line
			(start -0.67945 -0.305054)
			(end -0.12065 -0.305054)
			(stroke
				(width 0.1)
				(type default)
			)
			(layer "F.Fab")
		)
		(pad "1" smd circle
			(at -0.40005 0 180)
			(size 0 0)
			(layers "F.Cu" "F.Mask" "F.Paste")
			(net "P5V_AUX_VCC")
		)
		(pad "2" smd circle
			(at 0.40005 0 180)
			(size 0 0)
			(layers "F.Cu" "F.Mask" "F.Paste")
			(net "PWRGD_P5V_AUX_R")
		)
	)
)
